# S9S_MB_2U (Grand Teton) — schematic netlist excerpt (pin names and nets, part order shuffled) for the footprints in the layout excerpt that follows; sources: Cadence DE-HDL packaged netlist, KiCad conversion of 03242023_DA0F0TMBIJ0_F0T_Motherboard_J_brd_V01_OCP.brd

PC2221  Q_CAP  1UF 25V 10% X6S  pkg C0402  page 282 : A = PVNN_MAIN_CPU0_VCC ; B = GND
R2382  Q_RES  49.9 1% EMPTY  pkg 0402LF  page 266 : A = SVID_ALERT0_CPU0_R_N ; B = PVNN_TERM_CPU0

(kicad_pcb
	(version 20260206)
	(generator "pcbnew")
	(generator_version "10.0")
	(general
		(thickness 1.6)
		(legacy_teardrops no)
	)
	(paper "A4")
	(title_block
		(title "03242023_DA0F0TMBIJ0_F0T_Motherboard_J_brd_V01_OCP.brd")
		(comment 1 "Grand Teton / footprints 1340-1341 of 6105")
	)
	(layers
		(0 "F.Cu" signal "TOP")
		(4 "In1.Cu" signal "GND")
		(6 "In2.Cu" signal "IN1")
		(8 "In3.Cu" signal "GND1")
		(10 "In4.Cu" signal "IN2")
		(12 "In5.Cu" signal "GND2")
		(14 "In6.Cu" signal "IN3")
		(16 "In7.Cu" signal "GND3")
		(18 "In8.Cu" signal "VCC")
		(20 "In9.Cu" signal "VCC1")
		(22 "In10.Cu" signal "GND4")
		(24 "In11.Cu" signal "IN4")
		(26 "In12.Cu" signal "GND5")
		(28 "In13.Cu" signal "IN5")
		(30 "In14.Cu" signal "GND6")
		(32 "In15.Cu" signal "IN6")
		(34 "In16.Cu" signal "GND7")
		(2 "B.Cu" signal "BOTTOM")
		(9 "F.Adhes" user "F.Adhesive")
		(11 "B.Adhes" user "B.Adhesive")
		(13 "F.Paste" user "Package Geometry/Pastemask Top")
		(15 "B.Paste" user "Package Geometry/Pastemask Bottom")
		(5 "F.SilkS" user "Ref Des/Silkscreen Top")
		(7 "B.SilkS" user "Ref Des/Silkscreen Bottom")
		(1 "F.Mask" user "Board Geometry/Soldermask Top")
		(3 "B.Mask" user "Board Geometry/Soldermask Bottom")
		(17 "Dwgs.User" user "User.Drawings")
		(19 "Cmts.User" user "User.Comments")
		(21 "Eco1.User" user "User.Eco1")
		(23 "Eco2.User" user "User.Eco2")
		(25 "Edge.Cuts" user "Board Geometry/Outline")
		(27 "Margin" user)
		(31 "F.CrtYd" user "Package Geometry/Place Bound Top")
		(29 "B.CrtYd" user "Package Geometry/Place Bound Bottom")
		(35 "F.Fab" user "Ref Des/Assembly Top")
		(33 "B.Fab" user "Ref Des/Assembly Bottom")
	)
	(footprint ""
		(layer "F.Cu")
		(at 348.404942 -355.359462 180)
		(property "Reference" "R2382"
			(at 0 0 180)
			(layer "F.SilkS")
			(hide yes)
			(effects
				(font
					(size 1.27 1.27)
				)
			)
		)
		(property "Value" ""
			(at 0 0 180)
			(layer "F.Fab")
			(effects
				(font
					(size 1.27 1.27)
				)
			)
		)
		(duplicate_pad_numbers_are_jumpers no)
		(fp_line
			(start 0.7874 0.4064)
			(end -0.7874 0.4064)
			(stroke
				(width 0.1524)
				(type default)
			)
			(layer "F.SilkS")
		)
		(fp_line
			(start 0.7874 -0.4064)
			(end 0.7874 0.4064)
			(stroke
				(width 0.1524)
				(type default)
			)
			(layer "F.SilkS")
		)
		(fp_line
			(start -0.7874 0.4064)
			(end -0.7874 -0.4064)
			(stroke
				(width 0.1524)
				(type default)
			)
			(layer "F.SilkS")
		)
		(fp_line
			(start -0.7874 -0.4064)
			(end 0.7874 -0.4064)
			(stroke
				(width 0.1524)
				(type default)
			)
			(layer "F.SilkS")
		)
		(fp_line
			(start 0.67945 0.3048)
			(end 0.120396 0.3048)
			(stroke
				(width 0.1)
				(type default)
			)
			(layer "F.Fab")
		)
		(fp_line
			(start 0.67945 -0.3048)
			(end 0.67945 0.3048)
			(stroke
				(width 0.1)
				(type default)
			)
			(layer "F.Fab")
		)
		(fp_line
			(start 0.12065 -0.2794)
			(end 0.12065 -0.3048)
			(stroke
				(width 0.1)
				(type default)
			)
			(layer "F.Fab")
		)
		(fp_line
			(start 0.12065 -0.3048)
			(end 0.67945 -0.3048)
			(stroke
				(width 0.1)
				(type default)
			)
			(layer "F.Fab")
		)
		(fp_line
			(start 0.120396 0.3048)
			(end 0.120396 0.2794)
			(stroke
				(width 0.1)
				(type default)
			)
			(layer "F.Fab")
		)
		(fp_line
			(start 0.120396 0.2794)
			(end -0.12065 0.2794)
			(stroke
				(width 0.1)
				(type default)
			)
			(layer "F.Fab")
		)
		(fp_line
			(start -0.12065 0.3048)
			(end -0.67945 0.3048)
			(stroke
				(width 0.1)
				(type default)
			)
			(layer "F.Fab")
		)
		(fp_line
			(start -0.12065 0.2794)
			(end -0.12065 0.3048)
			(stroke
				(width 0.1)
				(type default)
			)
			(layer "F.Fab")
		)
		(fp_line
			(start -0.12065 -0.2794)
			(end 0.12065 -0.2794)
			(stroke
				(width 0.1)
				(type default)
			)
			(layer "F.Fab")
		)
		(fp_line
			(start -0.12065 -0.305054)
			(end -0.12065 -0.2794)
			(stroke
				(width 0.1)
				(type default)
			)
			(layer "F.Fab")
		)
		(fp_line
			(start -0.67945 0.3048)
			(end -0.67945 -0.305054)
			(stroke
				(width 0.1)
				(type default)
			)
			(layer "F.Fab")
		)
		(fp_line
			(start -0.67945 -0.305054)
			(end -0.12065 -0.305054)
			(stroke
				(width 0.1)
				(type default)
			)
			(layer "F.Fab")
		)
		(pad "1" smd circle
			(at -0.40005 0 180)
			(size 0 0)
			(layers "F.Cu" "F.Mask" "F.Paste")
			(net "SVID_ALERT0_CPU0_R_N")
		)
		(pad "2" smd circle
			(at 0.40005 0 180)
			(size 0 0)
			(layers "F.Cu" "F.Mask" "F.Paste")
			(net "PVNN_TERM_CPU0")
		)
	)
	(footprint ""
		(layer "F.Cu")
		(at 432.680618 -183.64327 180)
		(property "Reference" "PC2221"
			(at 0 0 180)
			(layer "F.SilkS")
			(hide yes)
			(effects
				(font
					(size 1.27 1.27)
				)
			)
		)
		(property "Value" ""
			(at 0 0 180)
			(layer "F.Fab")
			(effects
				(font
					(size 1.27 1.27)
				)
			)
		)
		(duplicate_pad_numbers_are_jumpers no)
		(fp_line
			(start 0.7874 0.4064)
			(end -0.7874 0.4064)
			(stroke
				(width 0.1524)
				(type default)
			)
			(layer "F.SilkS")
		)
		(fp_line
			(start 0.7874 -0.4064)
			(end 0.7874 0.4064)
			(stroke
				(width 0.1524)
				(type default)
			)
			(layer "F.SilkS")
		)
		(fp_line
			(start -0.7874 0.4064)
			(end -0.7874 -0.4064)
			(stroke
				(width 0.1524)
				(type default)
			)
			(layer "F.SilkS")
		)
		(fp_line
			(start -0.7874 -0.4064)
			(end 0.7874 -0.4064)
			(stroke
				(width 0.1524)
				(type default)
			)
			(layer "F.SilkS")
		)
		(fp_line
			(start 0.67945 0.3048)
			(end 0.120396 0.3048)
			(stroke
				(width 0.1)
				(type default)
			)
			(layer "F.Fab")
		)
		(fp_line
			(start 0.67945 -0.3048)
			(end 0.67945 0.3048)
			(stroke
				(width 0.1)
				(type default)
			)
			(layer "F.Fab")
		)
		(fp_line
			(start 0.12065 -0.2794)
			(end 0.12065 -0.3048)
			(stroke
				(width 0.1)
				(type default)
			)
			(layer "F.Fab")
		)
		(fp_line
			(start 0.12065 -0.3048)
			(end 0.67945 -0.3048)
			(stroke
				(width 0.1)
				(type default)
			)
			(layer "F.Fab")
		)
		(fp_line
			(start 0.120396 0.3048)
			(end 0.120396 0.2794)
			(stroke
				(width 0.1)
				(type default)
			)
			(layer "F.Fab")
		)
		(fp_line
			(start 0.120396 0.2794)
			(end -0.12065 0.2794)
			(stroke
				(width 0.1)
				(type default)
			)
			(layer "F.Fab")
		)
		(fp_line
			(start -0.12065 0.3048)
			(end -0.67945 0.3048)
			(stroke
				(width 0.1)
				(type default)
			)
			(layer "F.Fab")
		)
		(fp_line
			(start -0.12065 0.2794)
			(end -0.12065 0.3048)
			(stroke
				(width 0.1)
				(type default)
			)
			(layer "F.Fab")
		)
		(fp_line
			(start -0.12065 -0.2794)
			(end 0.12065 -0.2794)
			(stroke
				(width 0.1)
				(type default)
			)
			(layer "F.Fab")
		)
		(fp_line
			(start -0.12065 -0.305054)
			(end -0.12065 -0.2794)
			(stroke
				(width 0.1)
				(type default)
			)
			(layer "F.Fab")
		)
		(fp_line
			(start -0.67945 0.3048)
			(end -0.67945 -0.305054)
			(stroke
				(width 0.1)
				(type default)
			)
			(layer "F.Fab")
		)
		(fp_line
			(start -0.67945 -0.305054)
			(end -0.12065 -0.305054)
			(stroke
				(width 0.1)
				(type default)
			)
			(layer "F.Fab")
		)
		(pad "1" smd circle
			(at -0.40005 0 180)
			(size 0 0)
			(layers "F.Cu" "F.Mask" "F.Paste")
			(net "PVNN_MAIN_CPU0_VCC")
		)
		(pad "2" smd circle
			(at 0.40005 0 180)
			(size 0 0)
			(layers "F.Cu" "F.Mask" "F.Paste")
			(net "GND")
		)
	)
)
